# S9S_MB_2U (Grand Teton) — schematic netlist excerpt (pin names and nets, part order shuffled) for the footprints in the layout excerpt that follows; sources: Cadence DE-HDL packaged netlist, KiCad conversion of 03242023_DA0F0TMBIJ0_F0T_Motherboard_J_brd_V01_OCP.brd

PPQ8  MOSFET_NCH_1D3S  PSMNR58-30YLH EMPTY  pkg SOT1023  page 304
  \1\  = P12V_AUX
  \2\  = P12V_AUX
  \3\  = P12V_AUX
  \4\  = P12V_HSC_GATE_G4
  \5\  = P12V_MAIN_R

R2833  Q_RES  100K 1% EMPTY  pkg 0402LF  page 148 : A = FM_SWB_BIC_READY_N ; B = GND

(kicad_pcb
	(version 20260206)
	(generator "pcbnew")
	(generator_version "10.0")
	(general
		(thickness 1.6)
		(legacy_teardrops no)
	)
	(paper "A4")
	(title_block
		(title "03242023_DA0F0TMBIJ0_F0T_Motherboard_J_brd_V01_OCP.brd")
		(comment 1 "Grand Teton / footprints 3002-3003 of 6105")
	)
	(layers
		(0 "F.Cu" signal "TOP")
		(4 "In1.Cu" signal "GND")
		(6 "In2.Cu" signal "IN1")
		(8 "In3.Cu" signal "GND1")
		(10 "In4.Cu" signal "IN2")
		(12 "In5.Cu" signal "GND2")
		(14 "In6.Cu" signal "IN3")
		(16 "In7.Cu" signal "GND3")
		(18 "In8.Cu" signal "VCC")
		(20 "In9.Cu" signal "VCC1")
		(22 "In10.Cu" signal "GND4")
		(24 "In11.Cu" signal "IN4")
		(26 "In12.Cu" signal "GND5")
		(28 "In13.Cu" signal "IN5")
		(30 "In14.Cu" signal "GND6")
		(32 "In15.Cu" signal "IN6")
		(34 "In16.Cu" signal "GND7")
		(2 "B.Cu" signal "BOTTOM")
		(9 "F.Adhes" user "F.Adhesive")
		(11 "B.Adhes" user "B.Adhesive")
		(13 "F.Paste" user "Package Geometry/Pastemask Top")
		(15 "B.Paste" user "Package Geometry/Pastemask Bottom")
		(5 "F.SilkS" user "Ref Des/Silkscreen Top")
		(7 "B.SilkS" user "Ref Des/Silkscreen Bottom")
		(1 "F.Mask" user "Board Geometry/Soldermask Top")
		(3 "B.Mask" user "Board Geometry/Soldermask Bottom")
		(17 "Dwgs.User" user "User.Drawings")
		(19 "Cmts.User" user "User.Comments")
		(21 "Eco1.User" user "User.Eco1")
		(23 "Eco2.User" user "User.Eco2")
		(25 "Edge.Cuts" user "Board Geometry/Outline")
		(27 "Margin" user)
		(31 "F.CrtYd" user "Package Geometry/Place Bound Top")
		(29 "B.CrtYd" user "Package Geometry/Place Bound Bottom")
		(35 "F.Fab" user "Ref Des/Assembly Top")
		(33 "B.Fab" user "Ref Des/Assembly Bottom")
	)
	(footprint ""
		(layer "F.Cu")
		(at 271.966436 -398.78 90)
		(property "Reference" "PPQ8"
			(at -8.118348 -1.949196 0)
			(unlocked yes)
			(layer "F.SilkS")
			(effects
				(font
					(size 0.7874 0.5842)
					(thickness 0.1524)
				)
				(justify left)
			)
		)
		(property "Value" ""
			(at 0 0 90)
			(layer "F.Fab")
			(effects
				(font
					(size 1.27 1.27)
				)
			)
		)
		(duplicate_pad_numbers_are_jumpers no)
		(fp_line
			(start 2.350008 -2.649982)
			(end 2.350008 -2.4892)
			(stroke
				(width 0.1524)
				(type default)
			)
			(layer "F.SilkS")
		)
		(fp_line
			(start -2.350008 -2.649982)
			(end 2.350008 -2.649982)
			(stroke
				(width 0.1524)
				(type default)
			)
			(layer "F.SilkS")
		)
		(fp_line
			(start -2.350008 -2.4384)
			(end -2.350008 -2.649982)
			(stroke
				(width 0.1524)
				(type default)
			)
			(layer "F.SilkS")
		)
		(fp_line
			(start 2.350008 2.4892)
			(end 2.350008 2.649982)
			(stroke
				(width 0.1524)
				(type default)
			)
			(layer "F.SilkS")
		)
		(fp_line
			(start 2.350008 2.649982)
			(end -2.350008 2.649982)
			(stroke
				(width 0.1524)
				(type default)
			)
			(layer "F.SilkS")
		)
		(fp_line
			(start -2.350008 2.649982)
			(end -2.350008 2.413)
			(stroke
				(width 0.1524)
				(type default)
			)
			(layer "F.SilkS")
		)
		(fp_poly
			(pts
				(xy -3.717544 -1.905) (xy -4.758944 -2.3241) (xy -4.758944 -1.524)
			)
			(stroke
				(width 0)
				(type default)
			)
			(fill yes)
			(layer "F.SilkS")
		)
		(fp_line
			(start 2.350008 -2.649982)
			(end 2.350008 2.649982)
			(stroke
				(width 0.1)
				(type default)
			)
			(layer "F.Fab")
		)
		(fp_line
			(start -2.350008 -2.649982)
			(end 2.350008 -2.649982)
			(stroke
				(width 0.1)
				(type default)
			)
			(layer "F.Fab")
		)
		(fp_line
			(start 2.350008 2.649982)
			(end -2.350008 2.649982)
			(stroke
				(width 0.1)
				(type default)
			)
			(layer "F.Fab")
		)
		(fp_line
			(start -2.350008 2.649982)
			(end -2.350008 -2.649982)
			(stroke
				(width 0.1)
				(type default)
			)
			(layer "F.Fab")
		)
		(fp_poly
			(pts
				(xy -3.717544 -1.905) (xy -4.758944 -2.3241) (xy -4.758944 -1.524)
			)
			(stroke
				(width 0)
				(type default)
			)
			(fill yes)
			(layer "F.Fab")
		)
		(pad "1" smd rect
			(at -2.999994 -1.905)
			(size 0.7112 1.1684)
			(layers "F.Cu" "F.Mask" "F.Paste")
			(net "P12V_AUX")
		)
		(pad "2" smd rect
			(at -2.999994 -0.635)
			(size 0.7112 1.1684)
			(layers "F.Cu" "F.Mask" "F.Paste")
			(net "P12V_AUX")
		)
		(pad "3" smd rect
			(at -2.999994 0.635)
			(size 0.7112 1.1684)
			(layers "F.Cu" "F.Mask" "F.Paste")
			(net "P12V_AUX")
		)
		(pad "4" smd rect
			(at -2.999994 1.905)
			(size 0.7112 1.1684)
			(layers "F.Cu" "F.Mask" "F.Paste")
			(net "P12V_HSC_GATE_G4")
		)
		(pad "5" smd circle
			(at 0.925068 0)
			(size 0 0)
			(layers "F.Cu" "F.Mask" "F.Paste")
			(net "P12V_MAIN_R")
		)
		(zone
			(layer "F.Cu")
			(hatch none 0.5)
			(connect_pads
				(clearance 0)
			)
			(min_thickness 0.25)
			(keepout
				(tracks not_allowed)
				(vias allowed)
				(pads allowed)
				(copperpour not_allowed)
				(footprints allowed)
			)
			(placement
				(enabled no)
				(sheetname "")
			)
			(fill
				(thermal_gap 0.5)
				(thermal_bridge_width 0.5)
				(island_removal_mode 0)
			)
			(polygon
				(pts
					(xy 269.807436 -397.3322) (xy 274.125436 -397.3322) (xy 274.608036 -397.3322) (xy 274.608036 -396.4305)
					(xy 269.324836 -396.4305) (xy 269.324836 -397.3322)
				)
			)
		)
	)
	(footprint ""
		(layer "F.Cu")
		(at 424.204892 -391.632948 180)
		(property "Reference" "R2833"
			(at 0 0 180)
			(layer "F.SilkS")
			(hide yes)
			(effects
				(font
					(size 1.27 1.27)
				)
			)
		)
		(property "Value" ""
			(at 0 0 180)
			(layer "F.Fab")
			(effects
				(font
					(size 1.27 1.27)
				)
			)
		)
		(duplicate_pad_numbers_are_jumpers no)
		(fp_line
			(start 0.7874 0.4064)
			(end -0.7874 0.4064)
			(stroke
				(width 0.1524)
				(type default)
			)
			(layer "F.SilkS")
		)
		(fp_line
			(start 0.7874 -0.4064)
			(end 0.7874 0.4064)
			(stroke
				(width 0.1524)
				(type default)
			)
			(layer "F.SilkS")
		)
		(fp_line
			(start -0.7874 0.4064)
			(end -0.7874 -0.4064)
			(stroke
				(width 0.1524)
				(type default)
			)
			(layer "F.SilkS")
		)
		(fp_line
			(start -0.7874 -0.4064)
			(end 0.7874 -0.4064)
			(stroke
				(width 0.1524)
				(type default)
			)
			(layer "F.SilkS")
		)
		(fp_line
			(start 0.67945 0.3048)
			(end 0.120396 0.3048)
			(stroke
				(width 0.1)
				(type default)
			)
			(layer "F.Fab")
		)
		(fp_line
			(start 0.67945 -0.3048)
			(end 0.67945 0.3048)
			(stroke
				(width 0.1)
				(type default)
			)
			(layer "F.Fab")
		)
		(fp_line
			(start 0.12065 -0.2794)
			(end 0.12065 -0.3048)
			(stroke
				(width 0.1)
				(type default)
			)
			(layer "F.Fab")
		)
		(fp_line
			(start 0.12065 -0.3048)
			(end 0.67945 -0.3048)
			(stroke
				(width 0.1)
				(type default)
			)
			(layer "F.Fab")
		)
		(fp_line
			(start 0.120396 0.3048)
			(end 0.120396 0.2794)
			(stroke
				(width 0.1)
				(type default)
			)
			(layer "F.Fab")
		)
		(fp_line
			(start 0.120396 0.2794)
			(end -0.12065 0.2794)
			(stroke
				(width 0.1)
				(type default)
			)
			(layer "F.Fab")
		)
		(fp_line
			(start -0.12065 0.3048)
			(end -0.67945 0.3048)
			(stroke
				(width 0.1)
				(type default)
			)
			(layer "F.Fab")
		)
		(fp_line
			(start -0.12065 0.2794)
			(end -0.12065 0.3048)
			(stroke
				(width 0.1)
				(type default)
			)
			(layer "F.Fab")
		)
		(fp_line
			(start -0.12065 -0.2794)
			(end 0.12065 -0.2794)
			(stroke
				(width 0.1)
				(type default)
			)
			(layer "F.Fab")
		)
		(fp_line
			(start -0.12065 -0.305054)
			(end -0.12065 -0.2794)
			(stroke
				(width 0.1)
				(type default)
			)
			(layer "F.Fab")
		)
		(fp_line
			(start -0.67945 0.3048)
			(end -0.67945 -0.305054)
			(stroke
				(width 0.1)
				(type default)
			)
			(layer "F.Fab")
		)
		(fp_line
			(start -0.67945 -0.305054)
			(end -0.12065 -0.305054)
			(stroke
				(width 0.1)
				(type default)
			)
			(layer "F.Fab")
		)
		(pad "1" smd circle
			(at -0.40005 0 180)
			(size 0 0)
			(layers "F.Cu" "F.Mask" "F.Paste")
			(net "FM_SWB_BIC_READY_N")
		)
		(pad "2" smd circle
			(at 0.40005 0 180)
			(size 0 0)
			(layers "F.Cu" "F.Mask" "F.Paste")
			(net "GND")
		)
	)
)
